#ISCELL
  pure_quanta quanta_title_block_c *
  *
#CELL
  pure_quanta q_res *
  page179_i2
#ISCELL
  logical_power universal_gnd *
  page179_i3
#CELL
  pure_quanta emmitsburg_rev0p9 *
  page179_i4
